(kicad_pcb
	(version 20260206)
	(generator "pcbnew")
	(generator_version "10.0")
	(general
		(thickness 1.6)
		(legacy_teardrops no)
	)
	(paper "A4")
	(title_block
		(title "Bryce Canyon_IOM_IOC_16318-2_OCP.brd")
		(comment 1 "Bryce Canyon / footprints 855-860 of 1605")
	)
	(layers
		(0 "F.Cu" signal "TOP")
		(4 "In1.Cu" signal "L2GND")
		(6 "In2.Cu" signal "L3")
		(8 "In3.Cu" signal "L4VCC")
		(10 "In4.Cu" signal "L5VCC")
		(12 "In5.Cu" signal "L6")
		(14 "In6.Cu" signal "L7GND")
		(2 "B.Cu" signal "BOTTOM")
		(9 "F.Adhes" user "F.Adhesive")
		(11 "B.Adhes" user "B.Adhesive")
		(13 "F.Paste" user "Package Geometry/Pastemask Top")
		(15 "B.Paste" user "Package Geometry/Pastemask Bottom")
		(5 "F.SilkS" user "Ref Des/Silkscreen Top")
		(7 "B.SilkS" user "Ref Des/Silkscreen Bottom")
		(1 "F.Mask" user "Board Geometry/Soldermask Top")
		(3 "B.Mask" user "Board Geometry/Soldermask Bottom")
		(17 "Dwgs.User" user "User.Drawings")
		(19 "Cmts.User" user "User.Comments")
		(21 "Eco1.User" user "User.Eco1")
		(23 "Eco2.User" user "User.Eco2")
		(25 "Edge.Cuts" user "Board Geometry/Outline")
		(27 "Margin" user)
		(31 "F.CrtYd" user "Package Geometry/Place Bound Top")
		(29 "B.CrtYd" user "Package Geometry/Place Bound Bottom")
		(35 "F.Fab" user "Ref Des/Assembly Top")
		(33 "B.Fab" user "Ref Des/Assembly Bottom")
	)
	(footprint ""
		(layer "F.Cu")
		(at 167.5384 -133.858)
		(property "Reference" "C205"
			(at 0 0 0)
			(layer "F.SilkS")
			(hide yes)
			(effects
				(font
					(size 1.27 1.27)
				)
			)
		)
		(property "Value" "SC10U16V5KX-7-GP-U"
			(at -0.0762 -6.1214 0)
			(unlocked yes)
			(layer "F.Fab")
			(hide yes)
			(effects
				(font
					(size 1.016 1.016)
					(thickness 0.1524)
				)
			)
		)
		(property "Device Type" "C805H58"
			(at -0.0762 -8.1534 0)
			(unlocked yes)
			(layer "F.Fab")
			(hide yes)
			(effects
				(font
					(size 1.016 1.016)
					(thickness 0.1524)
				)
			)
		)
		(duplicate_pad_numbers_are_jumpers no)
		(fp_line
			(start 0.635 0)
			(end -0.635 0)
			(stroke
				(width 0.508)
				(type default)
			)
			(layer "F.SilkS")
		)
		(fp_rect
			(start -0.9652 1.778)
			(end 0.9652 -1.778)
			(stroke
				(width 0)
				(type default)
			)
			(fill no)
			(layer "F.CrtYd")
		)
		(fp_poly
			(pts
				(xy -0.9652 -1.778) (xy 0.9652 -1.778) (xy 0.9652 1.778) (xy -0.9652 1.778)
			)
			(stroke
				(width 0)
				(type default)
			)
			(fill no)
			(layer "F.Fab")
		)
		(pad "1" smd rect
			(at 0 -0.9652)
			(size 1.397 1.143)
			(layers "F.Cu" "F.Mask" "F.Paste")
			(net "P12V_STBY_VIN_PU4")
		)
		(pad "2" smd rect
			(at 0 0.9652)
			(size 1.397 1.143)
			(layers "F.Cu" "F.Mask" "F.Paste")
			(net "GND")
		)
	)
	(footprint ""
		(layer "F.Cu")
		(at 160.533588 -95.32747 90)
		(property "Reference" "R833"
			(at 0 0 90)
			(layer "F.SilkS")
			(hide yes)
			(effects
				(font
					(size 1.27 1.27)
				)
			)
		)
		(property "Value" "200KR2F-L-GP"
			(at 0.064008 -3.993896 90)
			(unlocked yes)
			(layer "F.Fab")
			(hide yes)
			(effects
				(font
					(size 1.016 1.016)
					(thickness 0.1524)
				)
			)
		)
		(property "Device Type" "R402H16"
			(at 0.064008 -5.517896 90)
			(unlocked yes)
			(layer "F.Fab")
			(hide yes)
			(effects
				(font
					(size 1.016 1.016)
					(thickness 0.1524)
				)
			)
		)
		(duplicate_pad_numbers_are_jumpers no)
		(fp_line
			(start 0.508 -0.9398)
			(end -0.508 -0.9398)
			(stroke
				(width 0.1524)
				(type default)
			)
			(layer "F.SilkS")
		)
		(fp_line
			(start -0.508 -0.9398)
			(end -0.508 0.9398)
			(stroke
				(width 0.1524)
				(type default)
			)
			(layer "F.SilkS")
		)
		(fp_rect
			(start -0.508 0.9398)
			(end 0.508 -0.9398)
			(stroke
				(width 0)
				(type default)
			)
			(fill no)
			(layer "F.CrtYd")
		)
		(fp_rect
			(start -0.508 0.9398)
			(end 0.508 -0.9398)
			(stroke
				(width 0)
				(type default)
			)
			(fill no)
			(layer "F.Fab")
		)
		(pad "1" smd custom
			(at 0 -0.4445 90)
			(size 0.1397 0.1397)
			(layers "F.Cu" "F.Mask" "F.Paste")
			(net "U43_VREF2")
			(options
				(clearance outline)
				(anchor circle)
			)
			(primitives
				(gr_poly
					(pts
						(arc
							(start -0.1778 -0.2794)
							(mid -0.249642 -0.249642)
							(end -0.2794 -0.1778)
						)
						(arc
							(start -0.2794 0.1778)
							(mid -0.249642 0.249642)
							(end -0.1778 0.2794)
						)
						(arc
							(start 0.1778 0.2794)
							(mid 0.249642 0.249642)
							(end 0.2794 0.1778)
						)
						(arc
							(start 0.2794 -0.1778)
							(mid 0.249642 -0.249642)
							(end 0.1778 -0.2794)
						)
					)
					(width 0)
					(fill yes)
				)
			)
		)
		(pad "2" smd custom
			(at 0 0.4445 90)
			(size 0.1397 0.1397)
			(layers "F.Cu" "F.Mask" "F.Paste")
			(net "P3V3_STBY")
			(options
				(clearance outline)
				(anchor circle)
			)
			(primitives
				(gr_poly
					(pts
						(arc
							(start -0.1778 -0.2794)
							(mid -0.249642 -0.249642)
							(end -0.2794 -0.1778)
						)
						(arc
							(start -0.2794 0.1778)
							(mid -0.249642 0.249642)
							(end -0.1778 0.2794)
						)
						(arc
							(start 0.1778 0.2794)
							(mid 0.249642 0.249642)
							(end 0.2794 0.1778)
						)
						(arc
							(start 0.2794 -0.1778)
							(mid 0.249642 -0.249642)
							(end 0.1778 -0.2794)
						)
					)
					(width 0)
					(fill yes)
				)
			)
		)
	)
	(footprint ""
		(layer "F.Cu")
		(at 99.453446 -142.7226 180)
		(property "Reference" "R423"
			(at 0 0 180)
			(layer "F.SilkS")
			(hide yes)
			(effects
				(font
					(size 1.27 1.27)
				)
			)
		)
		(property "Value" "4K7R2F-GP"
			(at 0.064008 -3.993896 180)
			(unlocked yes)
			(layer "F.Fab")
			(hide yes)
			(effects
				(font
					(size 1.016 1.016)
					(thickness 0.1524)
				)
			)
		)
		(property "Device Type" "R402H16"
			(at 0.064008 -5.517896 180)
			(unlocked yes)
			(layer "F.Fab")
			(hide yes)
			(effects
				(font
					(size 1.016 1.016)
					(thickness 0.1524)
				)
			)
		)
		(duplicate_pad_numbers_are_jumpers no)
		(fp_line
			(start 0.508 -0.9398)
			(end -0.508 -0.9398)
			(stroke
				(width 0.1524)
				(type default)
			)
			(layer "F.SilkS")
		)
		(fp_line
			(start -0.508 -0.9398)
			(end -0.508 0.9398)
			(stroke
				(width 0.1524)
				(type default)
			)
			(layer "F.SilkS")
		)
		(fp_rect
			(start -0.508 0.9398)
			(end 0.508 -0.9398)
			(stroke
				(width 0)
				(type default)
			)
			(fill no)
			(layer "F.CrtYd")
		)
		(fp_rect
			(start -0.508 0.9398)
			(end 0.508 -0.9398)
			(stroke
				(width 0)
				(type default)
			)
			(fill no)
			(layer "F.Fab")
		)
		(pad "1" smd custom
			(at 0 -0.4445 180)
			(size 0.1397 0.1397)
			(layers "F.Cu" "F.Mask" "F.Paste")
			(net "P3V3_STBY")
			(options
				(clearance outline)
				(anchor circle)
			)
			(primitives
				(gr_poly
					(pts
						(arc
							(start -0.1778 -0.2794)
							(mid -0.249642 -0.249642)
							(end -0.2794 -0.1778)
						)
						(arc
							(start -0.2794 0.1778)
							(mid -0.249642 0.249642)
							(end -0.1778 0.2794)
						)
						(arc
							(start 0.1778 0.2794)
							(mid 0.249642 0.249642)
							(end 0.2794 0.1778)
						)
						(arc
							(start 0.2794 -0.1778)
							(mid 0.249642 -0.249642)
							(end 0.1778 -0.2794)
						)
					)
					(width 0)
					(fill yes)
				)
			)
		)
		(pad "2" smd custom
			(at 0 0.4445 180)
			(size 0.1397 0.1397)
			(layers "F.Cu" "F.Mask" "F.Paste")
			(net "TCA9555_A0")
			(options
				(clearance outline)
				(anchor circle)
			)
			(primitives
				(gr_poly
					(pts
						(arc
							(start -0.1778 -0.2794)
							(mid -0.249642 -0.249642)
							(end -0.2794 -0.1778)
						)
						(arc
							(start -0.2794 0.1778)
							(mid -0.249642 0.249642)
							(end -0.1778 0.2794)
						)
						(arc
							(start 0.1778 0.2794)
							(mid 0.249642 0.249642)
							(end 0.2794 0.1778)
						)
						(arc
							(start 0.2794 -0.1778)
							(mid 0.249642 -0.249642)
							(end 0.1778 -0.2794)
						)
					)
					(width 0)
					(fill yes)
				)
			)
		)
	)
	(footprint ""
		(layer "F.Cu")
		(at 177.938684 -146.710146)
		(property "Reference" "PU1"
			(at 0 0 0)
			(layer "F.SilkS")
			(hide yes)
			(effects
				(font
					(size 1.27 1.27)
				)
			)
		)
		(property "Value" "TPS53318DQPR-GP"
			(at -5.022088 -6.851904 0)
			(unlocked yes)
			(layer "F.Fab")
			(hide yes)
			(effects
				(font
					(size 1.016 1.016)
					(thickness 0.1524)
				)
			)
		)
		(property "Device Type" "DFN22G6050-G6133H60"
			(at -5.022088 -8.375904 0)
			(unlocked yes)
			(layer "F.Fab")
			(hide yes)
			(effects
				(font
					(size 1.016 1.016)
					(thickness 0.1524)
				)
			)
		)
		(duplicate_pad_numbers_are_jumpers no)
		(fp_line
			(start -3.5052 -3.5179)
			(end -3.5052 -2.2479)
			(stroke
				(width 0.1524)
				(type default)
			)
			(layer "F.SilkS")
		)
		(fp_line
			(start -3.5052 2.2479)
			(end -3.5052 3.5179)
			(stroke
				(width 0.1524)
				(type default)
			)
			(layer "F.SilkS")
		)
		(fp_line
			(start -3.5052 3.5179)
			(end -2.2352 3.5179)
			(stroke
				(width 0.1524)
				(type default)
			)
			(layer "F.SilkS")
		)
		(fp_line
			(start -2.2352 -3.5179)
			(end -3.5052 -3.5179)
			(stroke
				(width 0.1524)
				(type default)
			)
			(layer "F.SilkS")
		)
		(fp_line
			(start -1.999996 -3.262122)
			(end -1.999996 -4.024122)
			(stroke
				(width 0.1524)
				(type default)
			)
			(layer "F.SilkS")
		)
		(fp_line
			(start -0.999998 3.262122)
			(end -0.999998 3.770122)
			(stroke
				(width 0.1524)
				(type default)
			)
			(layer "F.SilkS")
		)
		(fp_line
			(start 0.500126 -3.262122)
			(end 0.500126 -3.770122)
			(stroke
				(width 0.1524)
				(type default)
			)
			(layer "F.SilkS")
		)
		(fp_line
			(start 1.500124 3.262122)
			(end 1.500124 4.024122)
			(stroke
				(width 0.1524)
				(type default)
			)
			(layer "F.SilkS")
		)
		(fp_line
			(start 2.2352 3.5179)
			(end 3.5052 3.5179)
			(stroke
				(width 0.1524)
				(type default)
			)
			(layer "F.SilkS")
		)
		(fp_line
			(start 3.5052 3.5179)
			(end 3.5052 2.2479)
			(stroke
				(width 0.1524)
				(type default)
			)
			(layer "F.SilkS")
		)
		(fp_poly
			(pts
				(xy 3.5052 -3.5179) (xy 2.4765 -3.5179) (xy 3.5052 -2.4892)
			)
			(stroke
				(width 0)
				(type default)
			)
			(fill yes)
			(layer "F.SilkS")
		)
		(fp_rect
			(start -2.9972 2.5019)
			(end 2.9972 -2.5019)
			(stroke
				(width 0)
				(type default)
			)
			(fill no)
			(layer "F.CrtYd")
		)
		(fp_poly
			(pts
				(xy 3.556 -2.5019) (xy -2.9972 -2.5019) (xy -2.9972 2.5019) (xy 2.9972 2.5019) (xy 2.9972 -2.4892)
				(xy 3.556 -2.4892) (xy 3.556 3.5179) (xy -3.556 3.5179) (xy -3.556 -3.5179) (xy 3.556 -3.5179)
			)
			(stroke
				(width 0)
				(type default)
			)
			(fill no)
			(layer "F.CrtYd")
		)
		(fp_rect
			(start -3.556 3.5179)
			(end 3.556 -3.5179)
			(stroke
				(width 0)
				(type default)
			)
			(fill no)
			(layer "F.Fab")
		)
		(pad "1" smd rect
			(at 2.500122 -2.449322)
			(size 0.3048 1.1176)
			(layers "F.Cu" "F.Mask" "F.Paste")
			(net "P5V_VFB")
		)
		(pad "2" smd rect
			(at 1.999996 -2.449322)
			(size 0.3048 1.1176)
			(layers "F.Cu" "F.Mask" "F.Paste")
			(net "P5V_EN_R")
		)
		(pad "3" smd rect
			(at 1.500124 -2.449322)
			(size 0.3048 1.1176)
			(layers "F.Cu" "F.Mask" "F.Paste")
			(net "PWRGD_P5V_STBY")
		)
		(pad "4" smd rect
			(at 0.999998 -2.449322)
			(size 0.3048 1.1176)
			(layers "F.Cu" "F.Mask" "F.Paste")
			(net "P5V_VBST")
		)
		(pad "5" smd rect
			(at 0.500126 -2.449322)
			(size 0.3048 1.1176)
			(layers "F.Cu" "F.Mask" "F.Paste")
			(net "AGND_P5V")
		)
		(pad "6" smd rect
			(at 0 -2.449322)
			(size 0.3048 1.1176)
			(layers "F.Cu" "F.Mask" "F.Paste")
			(net "P5V_LL")
		)
		(pad "7" smd rect
			(at -0.500126 -2.449322)
			(size 0.3048 1.1176)
			(layers "F.Cu" "F.Mask" "F.Paste")
			(net "P5V_LL")
		)
		(pad "8" smd rect
			(at -0.999998 -2.449322)
			(size 0.3048 1.1176)
			(layers "F.Cu" "F.Mask" "F.Paste")
			(net "P5V_LL")
		)
		(pad "9" smd rect
			(at -1.500124 -2.449322)
			(size 0.3048 1.1176)
			(layers "F.Cu" "F.Mask" "F.Paste")
			(net "P5V_LL")
		)
		(pad "10" smd rect
			(at -1.999996 -2.449322)
			(size 0.3048 1.1176)
			(layers "F.Cu" "F.Mask" "F.Paste")
			(net "P5V_LL")
		)
		(pad "11" smd rect
			(at -2.500122 -2.449322)
			(size 0.3048 1.1176)
			(layers "F.Cu" "F.Mask" "F.Paste")
			(net "P5V_LL")
		)
		(pad "12" smd rect
			(at -2.500122 2.449322)
			(size 0.3048 1.1176)
			(layers "F.Cu" "F.Mask" "F.Paste")
			(net "P12V_STBY_VIN_PU1")
		)
		(pad "13" smd rect
			(at -1.999996 2.449322)
			(size 0.3048 1.1176)
			(layers "F.Cu" "F.Mask" "F.Paste")
			(net "P12V_STBY_VIN_PU1")
		)
		(pad "14" smd rect
			(at -1.500124 2.449322)
			(size 0.3048 1.1176)
			(layers "F.Cu" "F.Mask" "F.Paste")
			(net "P12V_STBY_VIN_PU1")
		)
		(pad "15" smd rect
			(at -0.999998 2.449322)
			(size 0.3048 1.1176)
			(layers "F.Cu" "F.Mask" "F.Paste")
			(net "P12V_STBY_VIN_PU1")
		)
		(pad "16" smd rect
			(at -0.500126 2.449322)
			(size 0.3048 1.1176)
			(layers "F.Cu" "F.Mask" "F.Paste")
			(net "P12V_STBY_VIN_PU1")
		)
		(pad "17" smd rect
			(at 0 2.449322)
			(size 0.3048 1.1176)
			(layers "F.Cu" "F.Mask" "F.Paste")
			(net "P12V_STBY_VIN_PU1")
		)
		(pad "18" smd rect
			(at 0.500126 2.449322)
			(size 0.3048 1.1176)
			(layers "F.Cu" "F.Mask" "F.Paste")
			(net "P5V_STBY_VREG")
		)
		(pad "19" smd rect
			(at 0.999998 2.449322)
			(size 0.3048 1.1176)
			(layers "F.Cu" "F.Mask" "F.Paste")
			(net "P12V_STBY_VDD_PU1")
		)
		(pad "20" smd rect
			(at 1.500124 2.449322)
			(size 0.3048 1.1176)
			(layers "F.Cu" "F.Mask" "F.Paste")
			(net "P5V_MODE")
		)
		(pad "21" smd rect
			(at 1.999996 2.449322)
			(size 0.3048 1.1176)
			(layers "F.Cu" "F.Mask" "F.Paste")
			(net "P5V_TRIP")
		)
		(pad "22" smd rect
			(at 2.500122 2.449322)
			(size 0.3048 1.1176)
			(layers "F.Cu" "F.Mask" "F.Paste")
			(net "P5V_RF")
		)
		(pad "23" smd custom
			(at 0 0)
			(size 0.83185 0.83185)
			(layers "F.Cu" "F.Mask" "F.Paste")
			(net "GND")
			(options
				(clearance outline)
				(anchor circle)
			)
			(primitives
				(gr_poly
					(pts
						(xy -2.7813 1.6637) (xy -2.7813 1.2954) (xy -3.048 1.2954) (xy -3.048 0.9525) (xy -2.7813 0.9525)
						(xy -2.7813 -0.9525) (xy -3.048 -0.9525) (xy -3.048 -1.2954) (xy -2.7813 -1.2954) (xy -2.7813 -1.6637)
						(xy 2.7813 -1.6637) (xy 2.7813 -1.2954) (xy 3.048 -1.2954) (xy 3.048 -0.9525) (xy 2.7813 -0.9525)
						(xy 2.7813 0.9525) (xy 3.048 0.9525) (xy 3.048 1.2954) (xy 2.7813 1.2954) (xy 2.7813 1.6637)
					)
					(width 0)
					(fill yes)
				)
			)
		)
	)
	(footprint ""
		(layer "F.Cu")
		(at 46.552358 -123.794012)
		(property "Reference" "R787"
			(at 0 0 0)
			(layer "F.SilkS")
			(hide yes)
			(effects
				(font
					(size 1.27 1.27)
				)
			)
		)
		(property "Value" "0R2J-2-GP"
			(at 0.064008 -3.993896 0)
			(unlocked yes)
			(layer "F.Fab")
			(hide yes)
			(effects
				(font
					(size 1.016 1.016)
					(thickness 0.1524)
				)
			)
		)
		(property "Device Type" "R402H16"
			(at 0.064008 -5.517896 0)
			(unlocked yes)
			(layer "F.Fab")
			(hide yes)
			(effects
				(font
					(size 1.016 1.016)
					(thickness 0.1524)
				)
			)
		)
		(duplicate_pad_numbers_are_jumpers no)
		(fp_line
			(start -0.508 -0.9398)
			(end -0.508 0.9398)
			(stroke
				(width 0.1524)
				(type default)
			)
			(layer "F.SilkS")
		)
		(fp_line
			(start 0.508 -0.9398)
			(end -0.508 -0.9398)
			(stroke
				(width 0.1524)
				(type default)
			)
			(layer "F.SilkS")
		)
		(fp_rect
			(start -0.508 0.9398)
			(end 0.508 -0.9398)
			(stroke
				(width 0)
				(type default)
			)
			(fill no)
			(layer "F.CrtYd")
		)
		(fp_rect
			(start -0.508 0.9398)
			(end 0.508 -0.9398)
			(stroke
				(width 0)
				(type default)
			)
			(fill no)
			(layer "F.Fab")
		)
		(pad "1" smd custom
			(at 0 -0.4445)
			(size 0.1397 0.1397)
			(layers "F.Cu" "F.Mask" "F.Paste")
			(net "FLA_CS_0_R")
			(options
				(clearance outline)
				(anchor circle)
			)
			(primitives
				(gr_poly
					(pts
						(arc
							(start -0.1778 -0.2794)
							(mid -0.249642 -0.249642)
							(end -0.2794 -0.1778)
						)
						(arc
							(start -0.2794 0.1778)
							(mid -0.249642 0.249642)
							(end -0.1778 0.2794)
						)
						(arc
							(start 0.1778 0.2794)
							(mid 0.249642 0.249642)
							(end 0.2794 0.1778)
						)
						(arc
							(start 0.2794 -0.1778)
							(mid 0.249642 -0.249642)
							(end 0.1778 -0.2794)
						)
					)
					(width 0)
					(fill yes)
				)
			)
		)
		(pad "2" smd custom
			(at 0 0.4445)
			(size 0.1397 0.1397)
			(layers "F.Cu" "F.Mask" "F.Paste")
			(net "BMC_CPU_EN")
			(options
				(clearance outline)
				(anchor circle)
			)
			(primitives
				(gr_poly
					(pts
						(arc
							(start -0.1778 -0.2794)
							(mid -0.249642 -0.249642)
							(end -0.2794 -0.1778)
						)
						(arc
							(start -0.2794 0.1778)
							(mid -0.249642 0.249642)
							(end -0.1778 0.2794)
						)
						(arc
							(start 0.1778 0.2794)
							(mid 0.249642 0.249642)
							(end 0.2794 0.1778)
						)
						(arc
							(start 0.2794 -0.1778)
							(mid 0.249642 -0.249642)
							(end 0.1778 -0.2794)
						)
					)
					(width 0)
					(fill yes)
				)
			)
		)
	)
	(footprint ""
		(layer "F.Cu")
		(at 63.3476 -148.7678 90)
		(property "Reference" "R189"
			(at 0 0 90)
			(layer "F.SilkS")
			(hide yes)
			(effects
				(font
					(size 1.27 1.27)
				)
			)
		)
		(property "Value" "499R2F-2-GP"
			(at 0.064008 -3.993896 90)
			(unlocked yes)
			(layer "F.Fab")
			(hide yes)
			(effects
				(font
					(size 1.016 1.016)
					(thickness 0.1524)
				)
			)
		)
		(property "Device Type" "R402H16"
			(at 0.064008 -5.517896 90)
			(unlocked yes)
			(layer "F.Fab")
			(hide yes)
			(effects
				(font
					(size 1.016 1.016)
					(thickness 0.1524)
				)
			)
		)
		(duplicate_pad_numbers_are_jumpers no)
		(fp_line
			(start 0.508 -0.9398)
			(end -0.508 -0.9398)
			(stroke
				(width 0.1524)
				(type default)
			)
			(layer "F.SilkS")
		)
		(fp_line
			(start -0.508 -0.9398)
			(end -0.508 0.9398)
			(stroke
				(width 0.1524)
				(type default)
			)
			(layer "F.SilkS")
		)
		(fp_rect
			(start -0.508 0.9398)
			(end 0.508 -0.9398)
			(stroke
				(width 0)
				(type default)
			)
			(fill no)
			(layer "F.CrtYd")
		)
		(fp_rect
			(start -0.508 0.9398)
			(end 0.508 -0.9398)
			(stroke
				(width 0)
				(type default)
			)
			(fill no)
			(layer "F.Fab")
		)
		(pad "1" smd custom
			(at 0 -0.4445 90)
			(size 0.1397 0.1397)
			(layers "F.Cu" "F.Mask" "F.Paste")
			(net "I2C_BMC_COMP_SCL_OUT")
			(options
				(clearance outline)
				(anchor circle)
			)
			(primitives
				(gr_poly
					(pts
						(arc
							(start -0.1778 -0.2794)
							(mid -0.249642 -0.249642)
							(end -0.2794 -0.1778)
						)
						(arc
							(start -0.2794 0.1778)
							(mid -0.249642 0.249642)
							(end -0.1778 0.2794)
						)
						(arc
							(start 0.1778 0.2794)
							(mid 0.249642 0.249642)
							(end 0.2794 0.1778)
						)
						(arc
							(start 0.2794 -0.1778)
							(mid 0.249642 -0.249642)
							(end 0.1778 -0.2794)
						)
					)
					(width 0)
					(fill yes)
				)
			)
		)
		(pad "2" smd custom
			(at 0 0.4445 90)
			(size 0.1397 0.1397)
			(layers "F.Cu" "F.Mask" "F.Paste")
			(net "P3V3_STBY")
			(options
				(clearance outline)
				(anchor circle)
			)
			(primitives
				(gr_poly
					(pts
						(arc
							(start -0.1778 -0.2794)
							(mid -0.249642 -0.249642)
							(end -0.2794 -0.1778)
						)
						(arc
							(start -0.2794 0.1778)
							(mid -0.249642 0.249642)
							(end -0.1778 0.2794)
						)
						(arc
							(start 0.1778 0.2794)
							(mid 0.249642 0.249642)
							(end 0.2794 0.1778)
						)
						(arc
							(start 0.2794 -0.1778)
							(mid 0.249642 -0.249642)
							(end 0.1778 -0.2794)
						)
					)
					(width 0)
					(fill yes)
				)
			)
		)
	)
)
